# S9S_MB_2U (Grand Teton) — schematic netlist excerpt (pin names and nets, part order shuffled) for the footprints in the layout excerpt that follows; sources: Cadence DE-HDL packaged netlist, KiCad conversion of 03242023_DA0F0TMBIJ0_F0T_Motherboard_J_brd_V01_OCP.brd

C349  Q_CAP  47UF 4V 20% X6S  pkg C0805  page 78 : A = PVCCIN_CPU1 ; B = GND
R132  Q_RES  0 5% CHIP  pkg 0402LF  page 125 : A = RST_CPU1_LVC1_R_N ; B = RST_CPU1_BUF_R_N
PC543_P1_4  Q_CAP  22UF 4V 20% X6S  pkg C0805  page 286 : A = PVCCIN_CPU1 ; B = GND

(kicad_pcb
	(version 20260206)
	(generator "pcbnew")
	(generator_version "10.0")
	(general
		(thickness 1.6)
		(legacy_teardrops no)
	)
	(paper "A4")
	(title_block
		(title "03242023_DA0F0TMBIJ0_F0T_Motherboard_J_brd_V01_OCP.brd")
		(comment 1 "Grand Teton / footprints 5406-5408 of 6105")
	)
	(layers
		(0 "F.Cu" signal "TOP")
		(4 "In1.Cu" signal "GND")
		(6 "In2.Cu" signal "IN1")
		(8 "In3.Cu" signal "GND1")
		(10 "In4.Cu" signal "IN2")
		(12 "In5.Cu" signal "GND2")
		(14 "In6.Cu" signal "IN3")
		(16 "In7.Cu" signal "GND3")
		(18 "In8.Cu" signal "VCC")
		(20 "In9.Cu" signal "VCC1")
		(22 "In10.Cu" signal "GND4")
		(24 "In11.Cu" signal "IN4")
		(26 "In12.Cu" signal "GND5")
		(28 "In13.Cu" signal "IN5")
		(30 "In14.Cu" signal "GND6")
		(32 "In15.Cu" signal "IN6")
		(34 "In16.Cu" signal "GND7")
		(2 "B.Cu" signal "BOTTOM")
		(9 "F.Adhes" user "F.Adhesive")
		(11 "B.Adhes" user "B.Adhesive")
		(13 "F.Paste" user "Package Geometry/Pastemask Top")
		(15 "B.Paste" user "Package Geometry/Pastemask Bottom")
		(5 "F.SilkS" user "Ref Des/Silkscreen Top")
		(7 "B.SilkS" user "Ref Des/Silkscreen Bottom")
		(1 "F.Mask" user "Board Geometry/Soldermask Top")
		(3 "B.Mask" user "Board Geometry/Soldermask Bottom")
		(17 "Dwgs.User" user "User.Drawings")
		(19 "Cmts.User" user "User.Comments")
		(21 "Eco1.User" user "User.Eco1")
		(23 "Eco2.User" user "User.Eco2")
		(25 "Edge.Cuts" user "Board Geometry/Outline")
		(27 "Margin" user)
		(31 "F.CrtYd" user "Package Geometry/Place Bound Top")
		(29 "B.CrtYd" user "Package Geometry/Place Bound Bottom")
		(35 "F.Fab" user "Ref Des/Assembly Top")
		(33 "B.Fab" user "Ref Des/Assembly Bottom")
	)
	(footprint ""
		(layer "B.Cu")
		(at 190.037212 -103.230426 90)
		(property "Reference" "R132"
			(at 0 0 90)
			(layer "B.SilkS")
			(hide yes)
			(effects
				(font
					(size 1.27 1.27)
				)
				(justify mirror)
			)
		)
		(property "Value" ""
			(at 0 0 90)
			(layer "B.Fab")
			(effects
				(font
					(size 1.27 1.27)
				)
				(justify mirror)
			)
		)
		(duplicate_pad_numbers_are_jumpers no)
		(fp_line
			(start 0.7874 -0.4064)
			(end -0.7874 -0.4064)
			(stroke
				(width 0.1524)
				(type default)
			)
			(layer "B.SilkS")
		)
		(fp_line
			(start -0.7874 -0.4064)
			(end -0.7874 0.4064)
			(stroke
				(width 0.1524)
				(type default)
			)
			(layer "B.SilkS")
		)
		(fp_line
			(start 0.7874 0.4064)
			(end 0.7874 -0.4064)
			(stroke
				(width 0.1524)
				(type default)
			)
			(layer "B.SilkS")
		)
		(fp_line
			(start -0.7874 0.4064)
			(end 0.7874 0.4064)
			(stroke
				(width 0.1524)
				(type default)
			)
			(layer "B.SilkS")
		)
		(fp_line
			(start 0.67945 -0.305054)
			(end 0.12065 -0.305054)
			(stroke
				(width 0.1)
				(type default)
			)
			(layer "B.Fab")
		)
		(fp_line
			(start 0.12065 -0.305054)
			(end 0.12065 -0.2794)
			(stroke
				(width 0.1)
				(type default)
			)
			(layer "B.Fab")
		)
		(fp_line
			(start -0.12065 -0.3048)
			(end -0.67945 -0.3048)
			(stroke
				(width 0.1)
				(type default)
			)
			(layer "B.Fab")
		)
		(fp_line
			(start -0.67945 -0.3048)
			(end -0.67945 0.3048)
			(stroke
				(width 0.1)
				(type default)
			)
			(layer "B.Fab")
		)
		(fp_line
			(start 0.12065 -0.2794)
			(end -0.12065 -0.2794)
			(stroke
				(width 0.1)
				(type default)
			)
			(layer "B.Fab")
		)
		(fp_line
			(start -0.12065 -0.2794)
			(end -0.12065 -0.3048)
			(stroke
				(width 0.1)
				(type default)
			)
			(layer "B.Fab")
		)
		(fp_line
			(start 0.12065 0.2794)
			(end 0.12065 0.3048)
			(stroke
				(width 0.1)
				(type default)
			)
			(layer "B.Fab")
		)
		(fp_line
			(start -0.120396 0.2794)
			(end 0.12065 0.2794)
			(stroke
				(width 0.1)
				(type default)
			)
			(layer "B.Fab")
		)
		(fp_line
			(start 0.67945 0.3048)
			(end 0.67945 -0.305054)
			(stroke
				(width 0.1)
				(type default)
			)
			(layer "B.Fab")
		)
		(fp_line
			(start 0.12065 0.3048)
			(end 0.67945 0.3048)
			(stroke
				(width 0.1)
				(type default)
			)
			(layer "B.Fab")
		)
		(fp_line
			(start -0.120396 0.3048)
			(end -0.120396 0.2794)
			(stroke
				(width 0.1)
				(type default)
			)
			(layer "B.Fab")
		)
		(fp_line
			(start -0.67945 0.3048)
			(end -0.120396 0.3048)
			(stroke
				(width 0.1)
				(type default)
			)
			(layer "B.Fab")
		)
		(pad "1" smd circle
			(at 0.40005 0 270)
			(size 0 0)
			(layers "B.Cu" "B.Mask" "B.Paste")
			(net "RST_CPU1_LVC1_R_N")
		)
		(pad "2" smd circle
			(at -0.40005 0 270)
			(size 0 0)
			(layers "B.Cu" "B.Mask" "B.Paste")
			(net "RST_CPU1_BUF_R_N")
		)
	)
	(footprint ""
		(layer "B.Cu")
		(at 119.95912 -244.82044 -90)
		(property "Reference" "C349"
			(at 0 0 90)
			(layer "B.SilkS")
			(hide yes)
			(effects
				(font
					(size 1.27 1.27)
				)
				(justify mirror)
			)
		)
		(property "Value" ""
			(at 0 0 90)
			(layer "B.Fab")
			(effects
				(font
					(size 1.27 1.27)
				)
				(justify mirror)
			)
		)
		(duplicate_pad_numbers_are_jumpers no)
		(fp_line
			(start -1.524 0.762)
			(end 1.524 0.762)
			(stroke
				(width 0.1524)
				(type default)
			)
			(layer "B.SilkS")
		)
		(fp_line
			(start 1.524 0.762)
			(end 1.524 -0.762)
			(stroke
				(width 0.1524)
				(type default)
			)
			(layer "B.SilkS")
		)
		(fp_line
			(start -1.524 -0.762)
			(end -1.524 0.762)
			(stroke
				(width 0.1524)
				(type default)
			)
			(layer "B.SilkS")
		)
		(fp_line
			(start 1.524 -0.762)
			(end -1.524 -0.762)
			(stroke
				(width 0.1524)
				(type default)
			)
			(layer "B.SilkS")
		)
		(fp_line
			(start -1.1049 0.724916)
			(end -1.1049 -0.724916)
			(stroke
				(width 0.1)
				(type default)
			)
			(layer "B.Fab")
		)
		(fp_line
			(start 1.1049 0.724916)
			(end -1.1049 0.724916)
			(stroke
				(width 0.1)
				(type default)
			)
			(layer "B.Fab")
		)
		(fp_line
			(start -1.1049 -0.724916)
			(end 1.1049 -0.724916)
			(stroke
				(width 0.1)
				(type default)
			)
			(layer "B.Fab")
		)
		(fp_line
			(start 1.1049 -0.724916)
			(end 1.1049 0.724916)
			(stroke
				(width 0.1)
				(type default)
			)
			(layer "B.Fab")
		)
		(pad "1" smd rect
			(at 0.889 0 270)
			(size 1.016 1.27)
			(layers "B.Cu" "B.Mask" "B.Paste")
			(net "PVCCIN_CPU1")
		)
		(pad "2" smd rect
			(at -0.889 0 270)
			(size 1.016 1.27)
			(layers "B.Cu" "B.Mask" "B.Paste")
			(net "GND")
		)
	)
	(footprint ""
		(layer "B.Cu")
		(at 122.992134 -324.792086 -90)
		(property "Reference" "PC543_P1_4"
			(at 0 0 90)
			(layer "B.SilkS")
			(hide yes)
			(effects
				(font
					(size 1.27 1.27)
				)
				(justify mirror)
			)
		)
		(property "Value" ""
			(at 0 0 90)
			(layer "B.Fab")
			(effects
				(font
					(size 1.27 1.27)
				)
				(justify mirror)
			)
		)
		(duplicate_pad_numbers_are_jumpers no)
		(fp_line
			(start -1.524 0.762)
			(end 1.524 0.762)
			(stroke
				(width 0.1524)
				(type default)
			)
			(layer "B.SilkS")
		)
		(fp_line
			(start 1.524 0.762)
			(end 1.524 -0.762)
			(stroke
				(width 0.1524)
				(type default)
			)
			(layer "B.SilkS")
		)
		(fp_line
			(start -1.524 -0.762)
			(end -1.524 0.762)
			(stroke
				(width 0.1524)
				(type default)
			)
			(layer "B.SilkS")
		)
		(fp_line
			(start 1.524 -0.762)
			(end -1.524 -0.762)
			(stroke
				(width 0.1524)
				(type default)
			)
			(layer "B.SilkS")
		)
		(fp_line
			(start -1.1049 0.724916)
			(end -1.1049 -0.724916)
			(stroke
				(width 0.1)
				(type default)
			)
			(layer "B.Fab")
		)
		(fp_line
			(start 1.1049 0.724916)
			(end -1.1049 0.724916)
			(stroke
				(width 0.1)
				(type default)
			)
			(layer "B.Fab")
		)
		(fp_line
			(start -1.1049 -0.724916)
			(end 1.1049 -0.724916)
			(stroke
				(width 0.1)
				(type default)
			)
			(layer "B.Fab")
		)
		(fp_line
			(start 1.1049 -0.724916)
			(end 1.1049 0.724916)
			(stroke
				(width 0.1)
				(type default)
			)
			(layer "B.Fab")
		)
		(pad "1" smd rect
			(at 0.889 0 270)
			(size 1.016 1.27)
			(layers "B.Cu" "B.Mask" "B.Paste")
			(net "PVCCIN_CPU1")
		)
		(pad "2" smd rect
			(at -0.889 0 270)
			(size 1.016 1.27)
			(layers "B.Cu" "B.Mask" "B.Paste")
			(net "GND")
		)
	)
)
